(kicad_pcb
	(version 20260206)
	(generator "pcbnew")
	(generator_version "10.0")
	(general
		(thickness 1.6)
		(legacy_teardrops no)
	)
	(paper "A4")
	(title_block
		(title "peb — Lightning_PEB_BRD.brd")
		(comment 1 "Lightning (Wiwynn / Facebook NVMe JBOF) / footprints 800-806 of 2563")
	)
	(layers
		(0 "F.Cu" signal "TOP")
		(4 "In1.Cu" signal "L2GND")
		(6 "In2.Cu" signal "L3")
		(8 "In3.Cu" signal "L4VCC")
		(10 "In4.Cu" signal "L5VCC")
		(12 "In5.Cu" signal "L6")
		(14 "In6.Cu" signal "L7GND")
		(2 "B.Cu" signal "BOTTOM")
		(9 "F.Adhes" user "F.Adhesive")
		(11 "B.Adhes" user "B.Adhesive")
		(13 "F.Paste" user "Package Geometry/Pastemask Top")
		(15 "B.Paste" user "Package Geometry/Pastemask Bottom")
		(5 "F.SilkS" user "Ref Des/Silkscreen Top")
		(7 "B.SilkS" user "Ref Des/Silkscreen Bottom")
		(1 "F.Mask" user "Board Geometry/Soldermask Top")
		(3 "B.Mask" user "Board Geometry/Soldermask Bottom")
		(17 "Dwgs.User" user "User.Drawings")
		(19 "Cmts.User" user "User.Comments")
		(21 "Eco1.User" user "User.Eco1")
		(23 "Eco2.User" user "User.Eco2")
		(25 "Edge.Cuts" user "Board Geometry/Outline")
		(27 "Margin" user)
		(31 "F.CrtYd" user "Package Geometry/Place Bound Top")
		(29 "B.CrtYd" user "Package Geometry/Place Bound Bottom")
		(35 "F.Fab" user "Ref Des/Assembly Top")
		(33 "B.Fab" user "Ref Des/Assembly Bottom")
	)
	(footprint ""
		(layer "F.Cu")
		(at 336.608166 -212.420454 180)
		(property "Reference" "C59"
			(at 0 0 180)
			(layer "F.SilkS")
			(hide yes)
			(effects
				(font
					(size 1.27 1.27)
				)
			)
		)
		(property "Value" "SCD22U10V2KX-1GP"
			(at 1.1811 -2.7051 180)
			(unlocked yes)
			(layer "F.Fab")
			(hide yes)
			(effects
				(font
					(size 1.016 1.016)
					(thickness 0.1524)
				)
			)
		)
		(property "Device Type" "C402H22"
			(at 1.1811 -4.2291 180)
			(unlocked yes)
			(layer "F.Fab")
			(hide yes)
			(effects
				(font
					(size 1.016 1.016)
					(thickness 0.1524)
				)
			)
		)
		(duplicate_pad_numbers_are_jumpers no)
		(fp_rect
			(start -0.4318 0.9525)
			(end 0.4318 -0.9525)
			(stroke
				(width 0)
				(type default)
			)
			(fill no)
			(layer "F.CrtYd")
		)
		(fp_rect
			(start -0.4318 0.9525)
			(end 0.4318 -0.9525)
			(stroke
				(width 0)
				(type default)
			)
			(fill no)
			(layer "F.Fab")
		)
		(pad "1" smd custom
			(at 0 -0.4445 180)
			(size 0.1524 0.1524)
			(layers "F.Cu" "F.Mask" "F.Paste")
			(net "PCIE_TX_CAP_N18")
			(options
				(clearance outline)
				(anchor circle)
			)
			(primitives
				(gr_poly
					(pts
						(arc
							(start 0.3048 -0.2032)
							(mid 0.275042 -0.275042)
							(end 0.2032 -0.3048)
						)
						(arc
							(start -0.2032 -0.3048)
							(mid -0.275042 -0.275042)
							(end -0.3048 -0.2032)
						)
						(arc
							(start -0.3048 0.2032)
							(mid -0.275042 0.275042)
							(end -0.2032 0.3048)
						)
						(arc
							(start 0.2032 0.3048)
							(mid 0.275042 0.275042)
							(end 0.3048 0.2032)
						)
					)
					(width 0)
					(fill yes)
				)
			)
		)
		(pad "2" smd custom
			(at 0 0.4445 180)
			(size 0.1524 0.1524)
			(layers "F.Cu" "F.Mask" "F.Paste")
			(net "PCIE_TX_N18")
			(options
				(clearance outline)
				(anchor circle)
			)
			(primitives
				(gr_poly
					(pts
						(arc
							(start 0.3048 -0.2032)
							(mid 0.275042 -0.275042)
							(end 0.2032 -0.3048)
						)
						(arc
							(start -0.2032 -0.3048)
							(mid -0.275042 -0.275042)
							(end -0.3048 -0.2032)
						)
						(arc
							(start -0.3048 0.2032)
							(mid -0.275042 0.275042)
							(end -0.2032 0.3048)
						)
						(arc
							(start 0.2032 0.3048)
							(mid 0.275042 0.275042)
							(end 0.3048 0.2032)
						)
					)
					(width 0)
					(fill yes)
				)
			)
		)
	)
	(footprint ""
		(layer "F.Cu")
		(at 57.4548 -145.837148)
		(property "Reference" "R418"
			(at 0 0 0)
			(layer "F.SilkS")
			(hide yes)
			(effects
				(font
					(size 1.27 1.27)
				)
			)
		)
		(property "Value" "10KR2F-2-GP"
			(at 0.064008 -3.993896 0)
			(unlocked yes)
			(layer "F.Fab")
			(hide yes)
			(effects
				(font
					(size 1.016 1.016)
					(thickness 0.1524)
				)
			)
		)
		(property "Device Type" "R402H16"
			(at 0.064008 -5.517896 0)
			(unlocked yes)
			(layer "F.Fab")
			(hide yes)
			(effects
				(font
					(size 1.016 1.016)
					(thickness 0.1524)
				)
			)
		)
		(duplicate_pad_numbers_are_jumpers no)
		(fp_line
			(start -0.508 -0.9398)
			(end -0.508 0.9398)
			(stroke
				(width 0.1524)
				(type default)
			)
			(layer "F.SilkS")
		)
		(fp_line
			(start 0.508 -0.9398)
			(end -0.508 -0.9398)
			(stroke
				(width 0.1524)
				(type default)
			)
			(layer "F.SilkS")
		)
		(fp_rect
			(start -0.508 0.9398)
			(end 0.508 -0.9398)
			(stroke
				(width 0)
				(type default)
			)
			(fill no)
			(layer "F.CrtYd")
		)
		(fp_rect
			(start -0.508 0.9398)
			(end 0.508 -0.9398)
			(stroke
				(width 0)
				(type default)
			)
			(fill no)
			(layer "F.Fab")
		)
		(pad "1" smd custom
			(at 0 -0.4445)
			(size 0.1397 0.1397)
			(layers "F.Cu" "F.Mask" "F.Paste")
			(net "P3V3_STBY")
			(options
				(clearance outline)
				(anchor circle)
			)
			(primitives
				(gr_poly
					(pts
						(arc
							(start -0.1778 -0.2794)
							(mid -0.249642 -0.249642)
							(end -0.2794 -0.1778)
						)
						(arc
							(start -0.2794 0.1778)
							(mid -0.249642 0.249642)
							(end -0.1778 0.2794)
						)
						(arc
							(start 0.1778 0.2794)
							(mid 0.249642 0.249642)
							(end 0.2794 0.1778)
						)
						(arc
							(start 0.2794 -0.1778)
							(mid 0.249642 -0.249642)
							(end 0.1778 -0.2794)
						)
					)
					(width 0)
					(fill yes)
				)
			)
		)
		(pad "2" smd custom
			(at 0 0.4445)
			(size 0.1397 0.1397)
			(layers "F.Cu" "F.Mask" "F.Paste")
			(net "BMC_I210_PERST_N")
			(options
				(clearance outline)
				(anchor circle)
			)
			(primitives
				(gr_poly
					(pts
						(arc
							(start -0.1778 -0.2794)
							(mid -0.249642 -0.249642)
							(end -0.2794 -0.1778)
						)
						(arc
							(start -0.2794 0.1778)
							(mid -0.249642 0.249642)
							(end -0.1778 0.2794)
						)
						(arc
							(start 0.1778 0.2794)
							(mid 0.249642 0.249642)
							(end 0.2794 0.1778)
						)
						(arc
							(start 0.2794 -0.1778)
							(mid 0.249642 -0.249642)
							(end 0.1778 -0.2794)
						)
					)
					(width 0)
					(fill yes)
				)
			)
		)
	)
	(footprint ""
		(layer "F.Cu")
		(at 13.8684 -82.1436 180)
		(property "Reference" "C638"
			(at 0 0 180)
			(layer "F.SilkS")
			(hide yes)
			(effects
				(font
					(size 1.27 1.27)
				)
			)
		)
		(property "Value" "SCD1U16V2KX-3GP"
			(at 1.1811 -2.7051 180)
			(unlocked yes)
			(layer "F.Fab")
			(hide yes)
			(effects
				(font
					(size 1.016 1.016)
					(thickness 0.1524)
				)
			)
		)
		(property "Device Type" "C402H22"
			(at 1.1811 -4.2291 180)
			(unlocked yes)
			(layer "F.Fab")
			(hide yes)
			(effects
				(font
					(size 1.016 1.016)
					(thickness 0.1524)
				)
			)
		)
		(duplicate_pad_numbers_are_jumpers no)
		(fp_rect
			(start -0.4318 0.9525)
			(end 0.4318 -0.9525)
			(stroke
				(width 0)
				(type default)
			)
			(fill no)
			(layer "F.CrtYd")
		)
		(fp_rect
			(start -0.4318 0.9525)
			(end 0.4318 -0.9525)
			(stroke
				(width 0)
				(type default)
			)
			(fill no)
			(layer "F.Fab")
		)
		(pad "1" smd custom
			(at 0 -0.4445 180)
			(size 0.1524 0.1524)
			(layers "F.Cu" "F.Mask" "F.Paste")
			(net "P0V9_I210")
			(options
				(clearance outline)
				(anchor circle)
			)
			(primitives
				(gr_poly
					(pts
						(arc
							(start 0.3048 -0.2032)
							(mid 0.275042 -0.275042)
							(end 0.2032 -0.3048)
						)
						(arc
							(start -0.2032 -0.3048)
							(mid -0.275042 -0.275042)
							(end -0.3048 -0.2032)
						)
						(arc
							(start -0.3048 0.2032)
							(mid -0.275042 0.275042)
							(end -0.2032 0.3048)
						)
						(arc
							(start 0.2032 0.3048)
							(mid 0.275042 0.275042)
							(end 0.3048 0.2032)
						)
					)
					(width 0)
					(fill yes)
				)
			)
		)
		(pad "2" smd custom
			(at 0 0.4445 180)
			(size 0.1524 0.1524)
			(layers "F.Cu" "F.Mask" "F.Paste")
			(net "GND")
			(options
				(clearance outline)
				(anchor circle)
			)
			(primitives
				(gr_poly
					(pts
						(arc
							(start 0.3048 -0.2032)
							(mid 0.275042 -0.275042)
							(end 0.2032 -0.3048)
						)
						(arc
							(start -0.2032 -0.3048)
							(mid -0.275042 -0.275042)
							(end -0.3048 -0.2032)
						)
						(arc
							(start -0.3048 0.2032)
							(mid -0.275042 0.275042)
							(end -0.2032 0.3048)
						)
						(arc
							(start 0.2032 0.3048)
							(mid 0.275042 0.275042)
							(end 0.3048 0.2032)
						)
					)
					(width 0)
					(fill yes)
				)
			)
		)
	)
	(footprint ""
		(layer "F.Cu")
		(at 125.3998 -95.0722 180)
		(property "Reference" "R428"
			(at 0 0 180)
			(layer "F.SilkS")
			(hide yes)
			(effects
				(font
					(size 1.27 1.27)
				)
			)
		)
		(property "Value" "10KR2F-2-GP"
			(at 0.064008 -3.993896 180)
			(unlocked yes)
			(layer "F.Fab")
			(hide yes)
			(effects
				(font
					(size 1.016 1.016)
					(thickness 0.1524)
				)
			)
		)
		(property "Device Type" "R402H16"
			(at 0.064008 -5.517896 180)
			(unlocked yes)
			(layer "F.Fab")
			(hide yes)
			(effects
				(font
					(size 1.016 1.016)
					(thickness 0.1524)
				)
			)
		)
		(duplicate_pad_numbers_are_jumpers no)
		(fp_line
			(start 0.508 -0.9398)
			(end -0.508 -0.9398)
			(stroke
				(width 0.1524)
				(type default)
			)
			(layer "F.SilkS")
		)
		(fp_line
			(start -0.508 -0.9398)
			(end -0.508 0.9398)
			(stroke
				(width 0.1524)
				(type default)
			)
			(layer "F.SilkS")
		)
		(fp_rect
			(start -0.508 0.9398)
			(end 0.508 -0.9398)
			(stroke
				(width 0)
				(type default)
			)
			(fill no)
			(layer "F.CrtYd")
		)
		(fp_rect
			(start -0.508 0.9398)
			(end 0.508 -0.9398)
			(stroke
				(width 0)
				(type default)
			)
			(fill no)
			(layer "F.Fab")
		)
		(pad "1" smd custom
			(at 0 -0.4445 180)
			(size 0.1397 0.1397)
			(layers "F.Cu" "F.Mask" "F.Paste")
			(net "P3V3_STBY")
			(options
				(clearance outline)
				(anchor circle)
			)
			(primitives
				(gr_poly
					(pts
						(arc
							(start -0.1778 -0.2794)
							(mid -0.249642 -0.249642)
							(end -0.2794 -0.1778)
						)
						(arc
							(start -0.2794 0.1778)
							(mid -0.249642 0.249642)
							(end -0.1778 0.2794)
						)
						(arc
							(start 0.1778 0.2794)
							(mid 0.249642 0.249642)
							(end 0.2794 0.1778)
						)
						(arc
							(start 0.2794 -0.1778)
							(mid 0.249642 -0.249642)
							(end 0.1778 -0.2794)
						)
					)
					(width 0)
					(fill yes)
				)
			)
		)
		(pad "2" smd custom
			(at 0 0.4445 180)
			(size 0.1397 0.1397)
			(layers "F.Cu" "F.Mask" "F.Paste")
			(net "I2C10_BUFF_EN")
			(options
				(clearance outline)
				(anchor circle)
			)
			(primitives
				(gr_poly
					(pts
						(arc
							(start -0.1778 -0.2794)
							(mid -0.249642 -0.249642)
							(end -0.2794 -0.1778)
						)
						(arc
							(start -0.2794 0.1778)
							(mid -0.249642 0.249642)
							(end -0.1778 0.2794)
						)
						(arc
							(start 0.1778 0.2794)
							(mid 0.249642 0.249642)
							(end 0.2794 0.1778)
						)
						(arc
							(start 0.2794 -0.1778)
							(mid 0.249642 -0.249642)
							(end 0.1778 -0.2794)
						)
					)
					(width 0)
					(fill yes)
				)
			)
		)
	)
	(footprint ""
		(layer "F.Cu")
		(at 88.9 -43.1546)
		(property "Reference" "PG7"
			(at 0 0 0)
			(layer "F.SilkS")
			(hide yes)
			(effects
				(font
					(size 1.27 1.27)
				)
			)
		)
		(property "Value" "GAP-CLOSE-PWR-3-GP"
			(at 0.0254 -6.5786 0)
			(unlocked yes)
			(layer "F.Fab")
			(hide yes)
			(effects
				(font
					(size 1.016 1.016)
					(thickness 0.1524)
				)
			)
		)
		(property "Device Type" "GAP-CLOSE-PWR-3"
			(at 0.0254 -8.255 0)
			(unlocked yes)
			(layer "F.Fab")
			(hide yes)
			(effects
				(font
					(size 1.016 1.016)
					(thickness 0.1524)
				)
			)
		)
		(duplicate_pad_numbers_are_jumpers no)
		(fp_rect
			(start -0.7112 0.4572)
			(end 0.7112 -0.4572)
			(stroke
				(width 0)
				(type default)
			)
			(fill no)
			(layer "F.CrtYd")
		)
		(fp_poly
			(pts
				(xy -0.7112 -0.4572) (xy 0.7112 -0.4572) (xy 0.7112 0.4572) (xy -0.7112 0.4572)
			)
			(stroke
				(width 0)
				(type default)
			)
			(fill no)
			(layer "F.Fab")
		)
		(pad "1" smd rect
			(at -0.3048 0)
			(size 0.6604 0.762)
			(layers "F.Cu" "F.Mask" "F.Paste")
			(net "P3V3_PWR")
		)
		(pad "2" smd rect
			(at 0.3048 0)
			(size 0.6604 0.762)
			(layers "F.Cu" "F.Mask" "F.Paste")
			(net "P3V3_STBY")
		)
	)
	(footprint ""
		(layer "F.Cu")
		(at 200.060052 -30.607 -90)
		(property "Reference" "U55"
			(at 0 0 270)
			(layer "F.SilkS")
			(hide yes)
			(effects
				(font
					(size 1.27 1.27)
				)
			)
		)
		(property "Value" "TCA9554PWR-GP"
			(at 0.127 -12.573 270)
			(unlocked yes)
			(layer "F.Fab")
			(hide yes)
			(effects
				(font
					(size 1.016 1.016)
					(thickness 0.1524)
				)
			)
		)
		(property "Device Type" "TSOIC16H48"
			(at 0.1016 -14.5796 270)
			(unlocked yes)
			(layer "F.Fab")
			(hide yes)
			(effects
				(font
					(size 1.016 1.016)
					(thickness 0.1524)
				)
			)
		)
		(duplicate_pad_numbers_are_jumpers no)
		(fp_line
			(start -2.921 3.81)
			(end -2.921 1.778)
			(stroke
				(width 0.508)
				(type default)
			)
			(layer "F.SilkS")
		)
		(fp_line
			(start 2.3622 1.778)
			(end -2.921 1.778)
			(stroke
				(width 0.1524)
				(type default)
			)
			(layer "F.SilkS")
		)
		(fp_line
			(start -2.54 0)
			(end -3.0988 0.5588)
			(stroke
				(width 0.1524)
				(type default)
			)
			(layer "F.SilkS")
		)
		(fp_line
			(start -2.54 0)
			(end -3.0988 -0.5588)
			(stroke
				(width 0.1524)
				(type default)
			)
			(layer "F.SilkS")
		)
		(fp_line
			(start -3.0988 -1.778)
			(end -3.0988 1.778)
			(stroke
				(width 0.1524)
				(type default)
			)
			(layer "F.SilkS")
		)
		(fp_line
			(start -3.0988 -1.778)
			(end 2.3622 -1.778)
			(stroke
				(width 0.1524)
				(type default)
			)
			(layer "F.SilkS")
		)
		(fp_line
			(start 2.3622 -1.778)
			(end 2.3622 1.778)
			(stroke
				(width 0.1524)
				(type default)
			)
			(layer "F.SilkS")
		)
		(fp_poly
			(pts
				(xy -2.4638 -1.778) (xy -2.4638 1.778) (xy 2.3622 1.778) (xy 2.3622 -1.778)
			)
			(stroke
				(width 0)
				(type default)
			)
			(fill yes)
			(layer "F.SilkS")
		)
		(fp_rect
			(start -3.175 4.064)
			(end 3.175 -4.064)
			(stroke
				(width 0)
				(type default)
			)
			(fill no)
			(layer "F.CrtYd")
		)
		(fp_poly
			(pts
				(xy -3.175 -4.064) (xy 3.175 -4.064) (xy 3.175 4.064) (xy -3.175 4.064)
			)
			(stroke
				(width 0)
				(type default)
			)
			(fill no)
			(layer "F.Fab")
		)
		(pad "1" smd rect
			(at -2.27584 2.8194 270)
			(size 0.3556 1.524)
			(layers "F.Cu" "F.Mask" "F.Paste")
			(net "U55_A0")
		)
		(pad "2" smd rect
			(at -1.6256 2.8194 270)
			(size 0.3556 1.524)
			(layers "F.Cu" "F.Mask" "F.Paste")
			(net "U55_A1")
		)
		(pad "3" smd rect
			(at -0.97536 2.8194 270)
			(size 0.3556 1.524)
			(layers "F.Cu" "F.Mask" "F.Paste")
			(net "U55_A2")
		)
		(pad "4" smd rect
			(at -0.32512 2.8194 270)
			(size 0.3556 1.524)
			(layers "F.Cu" "F.Mask" "F.Paste")
			(net "U55_P0")
		)
		(pad "5" smd rect
			(at 0.32512 2.8194 270)
			(size 0.3556 1.524)
			(layers "F.Cu" "F.Mask" "F.Paste")
			(net "Net_41")
		)
		(pad "6" smd rect
			(at 0.97536 2.8194 270)
			(size 0.3556 1.524)
			(layers "F.Cu" "F.Mask" "F.Paste")
			(net "Net_42")
		)
		(pad "7" smd rect
			(at 1.6256 2.8194 270)
			(size 0.3556 1.524)
			(layers "F.Cu" "F.Mask" "F.Paste")
			(net "Net_43")
		)
		(pad "8" smd rect
			(at 2.27584 2.8194 270)
			(size 0.3556 1.524)
			(layers "F.Cu" "F.Mask" "F.Paste")
			(net "GND")
		)
		(pad "9" smd rect
			(at 2.27584 -2.8194 270)
			(size 0.3556 1.524)
			(layers "F.Cu" "F.Mask" "F.Paste")
			(net "Net_44")
		)
		(pad "10" smd rect
			(at 1.6256 -2.8194 270)
			(size 0.3556 1.524)
			(layers "F.Cu" "F.Mask" "F.Paste")
			(net "Net_65")
		)
		(pad "11" smd rect
			(at 0.97536 -2.8194 270)
			(size 0.3556 1.524)
			(layers "F.Cu" "F.Mask" "F.Paste")
			(net "Net_66")
		)
		(pad "12" smd rect
			(at 0.32512 -2.8194 270)
			(size 0.3556 1.524)
			(layers "F.Cu" "F.Mask" "F.Paste")
			(net "Net_67")
		)
		(pad "13" smd rect
			(at -0.32512 -2.8194 270)
			(size 0.3556 1.524)
			(layers "F.Cu" "F.Mask" "F.Paste")
			(net "U55_INT_N")
		)
		(pad "14" smd rect
			(at -0.97536 -2.8194 270)
			(size 0.3556 1.524)
			(layers "F.Cu" "F.Mask" "F.Paste")
			(net "U55_SCL")
		)
		(pad "15" smd rect
			(at -1.6256 -2.8194 270)
			(size 0.3556 1.524)
			(layers "F.Cu" "F.Mask" "F.Paste")
			(net "U55_SDA")
		)
		(pad "16" smd rect
			(at -2.27584 -2.8194 270)
			(size 0.3556 1.524)
			(layers "F.Cu" "F.Mask" "F.Paste")
			(net "P3V3_STBY")
		)
	)
	(footprint ""
		(layer "F.Cu")
		(at 21.00326 -99.73691 90)
		(property "Reference" "R2947"
			(at 0 0 90)
			(layer "F.SilkS")
			(hide yes)
			(effects
				(font
					(size 1.27 1.27)
				)
			)
		)
		(property "Value" "10KR2F-2-GP"
			(at 0.064008 -3.993896 90)
			(unlocked yes)
			(layer "F.Fab")
			(hide yes)
			(effects
				(font
					(size 1.016 1.016)
					(thickness 0.1524)
				)
			)
		)
		(property "Device Type" "R402H16"
			(at 0.064008 -5.517896 90)
			(unlocked yes)
			(layer "F.Fab")
			(hide yes)
			(effects
				(font
					(size 1.016 1.016)
					(thickness 0.1524)
				)
			)
		)
		(duplicate_pad_numbers_are_jumpers no)
		(fp_line
			(start 0.508 -0.9398)
			(end -0.508 -0.9398)
			(stroke
				(width 0.1524)
				(type default)
			)
			(layer "F.SilkS")
		)
		(fp_line
			(start -0.508 -0.9398)
			(end -0.508 0.9398)
			(stroke
				(width 0.1524)
				(type default)
			)
			(layer "F.SilkS")
		)
		(fp_rect
			(start -0.508 0.9398)
			(end 0.508 -0.9398)
			(stroke
				(width 0)
				(type default)
			)
			(fill no)
			(layer "F.CrtYd")
		)
		(fp_rect
			(start -0.508 0.9398)
			(end 0.508 -0.9398)
			(stroke
				(width 0)
				(type default)
			)
			(fill no)
			(layer "F.Fab")
		)
		(pad "1" smd custom
			(at 0 -0.4445 90)
			(size 0.1397 0.1397)
			(layers "F.Cu" "F.Mask" "F.Paste")
			(net "P3V3_STBY")
			(options
				(clearance outline)
				(anchor circle)
			)
			(primitives
				(gr_poly
					(pts
						(arc
							(start -0.1778 -0.2794)
							(mid -0.249642 -0.249642)
							(end -0.2794 -0.1778)
						)
						(arc
							(start -0.2794 0.1778)
							(mid -0.249642 0.249642)
							(end -0.1778 0.2794)
						)
						(arc
							(start 0.1778 0.2794)
							(mid 0.249642 0.249642)
							(end 0.2794 0.1778)
						)
						(arc
							(start 0.2794 -0.1778)
							(mid 0.249642 -0.249642)
							(end 0.1778 -0.2794)
						)
					)
					(width 0)
					(fill yes)
				)
			)
		)
		(pad "2" smd custom
			(at 0 0.4445 90)
			(size 0.1397 0.1397)
			(layers "F.Cu" "F.Mask" "F.Paste")
			(net "FM_TPM_PRES_N")
			(options
				(clearance outline)
				(anchor circle)
			)
			(primitives
				(gr_poly
					(pts
						(arc
							(start -0.1778 -0.2794)
							(mid -0.249642 -0.249642)
							(end -0.2794 -0.1778)
						)
						(arc
							(start -0.2794 0.1778)
							(mid -0.249642 0.249642)
							(end -0.1778 0.2794)
						)
						(arc
							(start 0.1778 0.2794)
							(mid 0.249642 0.249642)
							(end 0.2794 0.1778)
						)
						(arc
							(start 0.2794 -0.1778)
							(mid 0.249642 -0.249642)
							(end 0.1778 -0.2794)
						)
					)
					(width 0)
					(fill yes)
				)
			)
		)
	)
)
